# S9S_MB_2U (Grand Teton) — schematic netlist excerpt (pin names and nets, part order shuffled) for the footprints in the layout excerpt that follows; sources: Cadence DE-HDL packaged netlist, KiCad conversion of 03242023_DA0F0TMBIJ0_F0T_Motherboard_J_brd_V01_OCP.brd

J7  SCONN288_ADR50017P130CC  SCONN288_ADR50017-P130CC IO  pkg DDR288S_1-1VXB  page 88
  VIN_BULK0  = P12V_S3_AUX_CPU0_NVDIMM
  RFU0  = TP_CHD_CPU0_DIMM1_FRU_0
  VIN_MGMT  = P3V3_AUX
  HSCL  = I3C_SPD_DDRABCD_CPU0_LVC1_SCL_6
  HSDA  = I3C_SPD_DDRABCD_CPU0_LVC1_SDA
  VSS0  = GND
  DQ0_A  = M_D_CPU0_SA_DQ<0>
  VSS1  = GND
  DQ1_A  = M_D_CPU0_SA_DQ<1>
  VSS2  = GND
  DQS0_A_T  = M_D_CPU0_SA_DQS_DP<0>
  DQS0_A_C  = M_D_CPU0_SA_DQS_DN<0>
  VSS3  = GND
  DQ4_A  = M_D_CPU0_SA_DQ<4>
  VSS4  = GND
  DQ5_A  = M_D_CPU0_SA_DQ<5>
  VSS5  = GND
  DQ8_A  = M_D_CPU0_SA_DQ<8>
  VSS6  = GND
  DQ9_A  = M_D_CPU0_SA_DQ<9>
  VSS7  = GND
  DQS1_A_T  = M_D_CPU0_SA_DQS_DP<1>
  DQS1_A_C  = M_D_CPU0_SA_DQS_DN<1>
  VSS8  = GND
  DQ12_A  = M_D_CPU0_SA_DQ<12>
  VSS9  = GND
  DQ13_A  = M_D_CPU0_SA_DQ<13>
  VSS10  = GND
  DQ16_A  = M_D_CPU0_SA_DQ<16>
  VSS11  = GND
  DQ17_A  = M_D_CPU0_SA_DQ<17>
  VSS12  = GND
  DQS2_A_T  = M_D_CPU0_SA_DQS_DP<2>
  DQS2_A_C  = M_D_CPU0_SA_DQS_DN<2>
  VSS13  = GND
  DQ20_A  = M_D_CPU0_SA_DQ<20>
  VSS14  = GND
  DQ21_A  = M_D_CPU0_SA_DQ<21>
  VSS15  = GND
  DQ24_A  = M_D_CPU0_SA_DQ<24>
  VSS16  = GND
  DQ25_A  = M_D_CPU0_SA_DQ<25>
  VSS17  = GND
  DQS3_A_T  = M_D_CPU0_SA_DQS_DP<3>
  DQS3_A_C  = M_D_CPU0_SA_DQS_DN<3>
  VSS18  = GND
  DQ28_A  = M_D_CPU0_SA_DQ<28>
  VSS19  = GND
  DQ29_A  = M_D_CPU0_SA_DQ<29>
  VSS20  = GND
  CB0_A  = M_D_CPU0_SA_CB<0>
  VSS21  = GND
  CB1_A  = M_D_CPU0_SA_CB<1>
  VSS22  = GND
  DQS4_A_T  = M_D_CPU0_SA_DQS_DP<4>
  DQS4_A_C  = M_D_CPU0_SA_DQS_DN<4>
  VSS23  = GND
  CB4_A  = M_D_CPU0_SA_CB<4>
  VSS24  = GND
  CB5_A  = M_D_CPU0_SA_CB<5>
  VSS25  = GND
  ALERT_N  = M_D_CPU0_ALERT_N
  VSS26  = GND
  CS0_A_N  = M_D_CPU0_SA_CS_N<0>
  VSS27  = GND
  CA0_A  = M_D_CPU0_SA_CA<0>
  VSS28  = GND
  CA2_A  = M_D_CPU0_SA_CA<2>
  VSS29  = GND
  CA4_A  = M_D_CPU0_SA_CA<4>
  VSS30  = GND
  CA6_A  = M_D_CPU0_SA_CA<6>
  VSS31  = GND
  PAR_A  = M_D_CPU0_SA_PAR
  VSS32  = GND
  CA0_B  = M_D_CPU0_SB_CA<0>
  VSS33  = GND
  CA2_B  = M_D_CPU0_SB_CA<2>
  VSS34  = GND
  CA4_B  = M_D_CPU0_SB_CA<4>
  VSS35  = GND
  CA6_B  = M_D_CPU0_SB_CA<6>
  VSS36  = GND
  CS0_B_N  = M_D_CPU0_SB_CS_N<0>
  VSS37  = GND
  \lbd||rsp_a_n\  = M_D_CPU0_SA_RSP<0>
  \lbs||rsp_b_n\  = M_D_CPU0_SB_RSP<0>
  VSS38  = GND
  CB4_B  = M_D_CPU0_SB_CB<4>
  VSS39  = GND
  CB5_B  = M_D_CPU0_SB_CB<5>
  VSS40  = GND
  \dqs9_b_t||tdqs9_b_t||dbi4_b_n\  = M_D_CPU0_SB_DQS_DP<9>
  \dqs9_b_c||tdqs9_b_c\  = M_D_CPU0_SB_DQS_DN<9>
  VSS41  = GND
  CB0_B  = M_D_CPU0_SB_CB<0>
  VSS42  = GND
  CB1_B  = M_D_CPU0_SB_CB<1>
  VSS43  = GND
  DQ0_B  = M_D_CPU0_SB_DQ<0>
  VSS44  = GND
  DQ1_B  = M_D_CPU0_SB_DQ<1>
  VSS45  = GND
  DQS0_B_T  = M_D_CPU0_SB_DQS_DP<0>
  DQS0_B_C  = M_D_CPU0_SB_DQS_DN<0>
  VSS46  = GND
  DQ4_B  = M_D_CPU0_SB_DQ<4>
  VSS47  = GND
  DQ5_B  = M_D_CPU0_SB_DQ<5>
  VSS48  = GND
  DQ8_B  = M_D_CPU0_SB_DQ<8>
  VSS49  = GND
  DQ9_B  = M_D_CPU0_SB_DQ<9>
  VSS50  = GND
  DQS1_B_T  = M_D_CPU0_SB_DQS_DP<1>
  DQS1_B_C  = M_D_CPU0_SB_DQS_DN<1>
  VSS51  = GND
  DQ12_B  = M_D_CPU0_SB_DQ<12>
  VSS52  = GND
  DQ13_B  = M_D_CPU0_SB_DQ<13>
  VSS53  = GND
  DQ16_B  = M_D_CPU0_SB_DQ<16>
  VSS54  = GND
  DQ17_B  = M_D_CPU0_SB_DQ<17>
  VSS55  = GND
  DQS2_B_T  = M_D_CPU0_SB_DQS_DP<2>
  DQS2_B_C  = M_D_CPU0_SB_DQS_DN<2>
  VSS56  = GND
  DQ20_B  = M_D_CPU0_SB_DQ<20>
  VSS57  = GND
  DQ21_B  = M_D_CPU0_SB_DQ<21>
  VSS58  = GND
  DQ24_B  = M_D_CPU0_SB_DQ<24>
  VSS59  = GND
  DQ25_B  = M_D_CPU0_SB_DQ<25>
  VSS60  = GND
  DQS3_B_T  = M_D_CPU0_SB_DQS_DP<3>
  DQS3_B_C  = M_D_CPU0_SB_DQS_DN<3>
  VSS61  = GND
  DQ28_B  = M_D_CPU0_SB_DQ<28>
  VSS62  = GND
  DQ29_B  = M_D_CPU0_SB_DQ<29>
  VSS63  = GND
  RFU1  = TP_CHD_CPU0_DIMM1_FRU_1
  VIN_BULK1  = P12V_S3_AUX_CPU0_NVDIMM
  VIN_BULK2  = P12V_S3_AUX_CPU0_NVDIMM
  \pwr_good||fail_n\  = PWRGD_CHD_CPU0_DIMM1
  HSA  = PD_CHD_CPU0_DIMM1_SAA
  RFU2  = TP_CHD_CPU0_DIMM1_FRU_2
  RFU3  = TP_CHD_CPU0_DIMM1_FRU_3
  VSS64  = GND
  DQ2_A  = M_D_CPU0_SA_DQ<2>
  VSS65  = GND
  DQ3_A  = M_D_CPU0_SA_DQ<3>
  VSS66  = GND
  \dqs5_a_c||tdqs5_a_c||dqs5_a_t||tdqs5_a_t\  = M_D_CPU0_SA_DQS_DN<5>
  \dqs5_a_t||tdqs5_a_t\  = M_D_CPU0_SA_DQS_DP<5>
  VSS67  = GND
  DQ6_A  = M_D_CPU0_SA_DQ<6>
  VSS68  = GND
  DQ7_A  = M_D_CPU0_SA_DQ<7>
  VSS69  = GND
  DQ10_A  = M_D_CPU0_SA_DQ<10>
  VSS70  = GND
  DQ11_A  = M_D_CPU0_SA_DQ<11>
  VSS71  = GND
  \dqs6_a_c||tdqs6_a_c||dqs6_a_t||tdqs6_a_t\  = M_D_CPU0_SA_DQS_DN<6>
  \dqs6_a_t||tdqs6_a_t\  = M_D_CPU0_SA_DQS_DP<6>
  VSS72  = GND
  DQ14_A  = M_D_CPU0_SA_DQ<14>
  VSS73  = GND
  DQ15_A  = M_D_CPU0_SA_DQ<15>
  VSS74  = GND
  DQ18_A  = M_D_CPU0_SA_DQ<18>
  VSS75  = GND
  DQ19_A  = M_D_CPU0_SA_DQ<19>
  VSS76  = GND
  \dqs7_a_c||tdqs7_a_c\  = M_D_CPU0_SA_DQS_DN<7>
  \dqs7_a_t||tdqs7_a_t\  = M_D_CPU0_SA_DQS_DP<7>
  VSS77  = GND
  DQ22_A  = M_D_CPU0_SA_DQ<22>
  VSS78  = GND
  DQ23_A  = M_D_CPU0_SA_DQ<23>
  VSS79  = GND
  DQ26_A  = M_D_CPU0_SA_DQ<26>
  VSS80  = GND
  DQ27_A  = M_D_CPU0_SA_DQ<27>
  VSS81  = GND
  \dqs8_a_c||tdqs8_a_c\  = M_D_CPU0_SA_DQS_DN<8>
  \dqs8_a_t||tdqs8_a_t\  = M_D_CPU0_SA_DQS_DP<8>
  VSS82  = GND
  DQ30_A  = M_D_CPU0_SA_DQ<30>
  VSS83  = GND
  DQ31_A  = M_D_CPU0_SA_DQ<31>
  VSS84  = GND
  CB2_A  = M_D_CPU0_SA_CB<2>
  VSS85  = GND
  CB3_A  = M_D_CPU0_SA_CB<3>
  VSS86  = GND
  \dqs9_a_c||tdqs9_a_c\  = M_D_CPU0_SA_DQS_DN<9>
  \dqs9_a_t||tdqs9_a_t\  = M_D_CPU0_SA_DQS_DP<9>
  VSS87  = GND
  CB6_A  = M_D_CPU0_SA_CB<6>
  VSS88  = GND
  CB7_A  = M_D_CPU0_SA_CB<7>
  VSS89  = GND
  RESET_N  = RST_M_CD_CPU0_FPGA_N
  VSS90  = GND
  CS1_A_N  = M_D_CPU0_SA_CS_N<1>
  VSS91  = GND
  CA1_A  = M_D_CPU0_SA_CA<1>
  VSS92  = GND
  CA3_A  = M_D_CPU0_SA_CA<3>
  VSS93  = GND
  CA5_A  = M_D_CPU0_SA_CA<5>
  VSS94  = GND
  CK_T  = M_D_CPU0_CLK_DP<0>
  CK_C  = M_D_CPU0_CLK_DN<0>
  VSS95  = GND
  RFU4  = TP_CHD_CPU0_DIMM1_FRU_4
  CA1_B  = M_D_CPU0_SB_CA<1>
  VSS96  = GND
  CA3_B  = M_D_CPU0_SB_CA<3>
  VSS97  = GND
  CA5_B  = M_D_CPU0_SB_CA<5>
  VSS98  = GND
  PAR_B  = M_D_CPU0_SB_PAR
  VSS99  = GND
  CS1_B_N  = M_D_CPU0_SB_CS_N<1>
  VSS100  = GND
  RFU5  = TP_CHD_CPU0_DIMM1_FRU_5
  RFU6  = TP_CHD_CPU0_DIMM1_FRU_6
  VSS101  = GND
  CB6_B  = M_D_CPU0_SB_CB<6>
  VSS102  = GND
  CB7_B  = M_D_CPU0_SB_CB<7>
  VSS103  = GND
  DQS4_B_C  = M_D_CPU0_SB_DQS_DN<4>
  DQS4_B_T  = M_D_CPU0_SB_DQS_DP<4>
  VSS104  = GND
  CB2_B  = M_D_CPU0_SB_CB<2>
  VSS105  = GND
  CB3_B  = M_D_CPU0_SB_CB<3>
  VSS106  = GND
  DQ2_B  = M_D_CPU0_SB_DQ<2>
  VSS107  = GND
  DQ3_B  = M_D_CPU0_SB_DQ<3>
  VSS108  = GND
  \dqs5_b_c||tdqs5_b_c\  = M_D_CPU0_SB_DQS_DN<5>
  \dqs5_b_t||tdqs5_b_t\  = M_D_CPU0_SB_DQS_DP<5>
  VSS109  = GND
  DQ6_B  = M_D_CPU0_SB_DQ<6>
  VSS110  = GND
  DQ7_B  = M_D_CPU0_SB_DQ<7>
  VSS111  = GND
  DQ10_B  = M_D_CPU0_SB_DQ<10>
  VSS112  = GND
  DQ11_B  = M_D_CPU0_SB_DQ<11>
  VSS113  = GND
  \dqs6_b_c||tdqs6_b_c\  = M_D_CPU0_SB_DQS_DN<6>
  \dqs6_b_t||tdqs6_b_t\  = M_D_CPU0_SB_DQS_DP<6>
  VSS114  = GND
  DQ14_B  = M_D_CPU0_SB_DQ<14>
  VSS115  = GND
  DQ15_B  = M_D_CPU0_SB_DQ<15>
  VSS116  = GND
  DQ18_B  = M_D_CPU0_SB_DQ<18>
  VSS117  = GND
  DQ19_B  = M_D_CPU0_SB_DQ<19>
  VSS118  = GND
  \dqs7_b_c||tdqs7_b_c\  = M_D_CPU0_SB_DQS_DN<7>
  \dqs7_b_t||tdqs7_b_t\  = M_D_CPU0_SB_DQS_DP<7>
  VSS119  = GND
  DQ22_B  = M_D_CPU0_SB_DQ<22>
  VSS120  = GND
  DQ23_B  = M_D_CPU0_SB_DQ<23>
  VSS121  = GND
  DQ26_B  = M_D_CPU0_SB_DQ<26>
  VSS122  = GND
  DQ27_B  = M_D_CPU0_SB_DQ<27>
  VSS123  = GND
  \dqs8_b_c||tdqs8_b_c\  = M_D_CPU0_SB_DQS_DN<8>
  \dqs8_b_t||tdqs8_b_t\  = M_D_CPU0_SB_DQS_DP<8>
  VSS124  = GND
  DQ30_B  = M_D_CPU0_SB_DQ<30>
  VSS125  = GND
  DQ31_B  = M_D_CPU0_SB_DQ<31>
  VSS126  = GND
  G1  = GND
  G2  = GND
  G3  = GND

(kicad_pcb
	(version 20260206)
	(generator "pcbnew")
	(generator_version "10.0")
	(general
		(thickness 1.6)
		(legacy_teardrops no)
	)
	(paper "A4")
	(title_block
		(title "03242023_DA0F0TMBIJ0_F0T_Motherboard_J_brd_V01_OCP.brd")
		(comment 1 "Grand Teton / footprint 37 of 6105 (J7), pads 1-45 of 291")
	)
	(layers
		(0 "F.Cu" signal "TOP")
		(4 "In1.Cu" signal "GND")
		(6 "In2.Cu" signal "IN1")
		(8 "In3.Cu" signal "GND1")
		(10 "In4.Cu" signal "IN2")
		(12 "In5.Cu" signal "GND2")
		(14 "In6.Cu" signal "IN3")
		(16 "In7.Cu" signal "GND3")
		(18 "In8.Cu" signal "VCC")
		(20 "In9.Cu" signal "VCC1")
		(22 "In10.Cu" signal "GND4")
		(24 "In11.Cu" signal "IN4")
		(26 "In12.Cu" signal "GND5")
		(28 "In13.Cu" signal "IN5")
		(30 "In14.Cu" signal "GND6")
		(32 "In15.Cu" signal "IN6")
		(34 "In16.Cu" signal "GND7")
		(2 "B.Cu" signal "BOTTOM")
		(9 "F.Adhes" user "F.Adhesive")
		(11 "B.Adhes" user "B.Adhesive")
		(13 "F.Paste" user "Package Geometry/Pastemask Top")
		(15 "B.Paste" user "Package Geometry/Pastemask Bottom")
		(5 "F.SilkS" user "Ref Des/Silkscreen Top")
		(7 "B.SilkS" user "Ref Des/Silkscreen Bottom")
		(1 "F.Mask" user "Board Geometry/Soldermask Top")
		(3 "B.Mask" user "Board Geometry/Soldermask Bottom")
		(17 "Dwgs.User" user "User.Drawings")
		(19 "Cmts.User" user "User.Comments")
		(21 "Eco1.User" user "User.Eco1")
		(23 "Eco2.User" user "User.Eco2")
		(25 "Edge.Cuts" user "Board Geometry/Outline")
		(27 "Margin" user)
		(31 "F.CrtYd" user "Package Geometry/Place Bound Top")
		(29 "B.CrtYd" user "Package Geometry/Place Bound Bottom")
		(35 "F.Fab" user "Ref Des/Assembly Top")
		(33 "B.Fab" user "Ref Des/Assembly Bottom")
	)
	(footprint ""
		(layer "F.Cu")
		(at 258.130548 -258.091686)
		(property "Reference" "J7"
			(at -3.683 -81.702148 0)
			(unlocked yes)
			(layer "F.SilkS")
			(effects
				(font
					(size 0.7874 0.5842)
					(thickness 0.1524)
				)
				(justify left)
			)
		)
		(property "Value" ""
			(at 0 0 0)
			(layer "F.Fab")
			(effects
				(font
					(size 1.27 1.27)
				)
			)
		)
		(duplicate_pad_numbers_are_jumpers no)
		(pad "1" smd rect
			(at -2.050034 -63.324994 270)
			(size 0.519938 1.4986)
			(layers "F.Cu" "F.Mask" "F.Paste")
			(net "P12V_S3_AUX_CPU0_NVDIMM")
		)
		(pad "2" smd rect
			(at -2.050034 -62.47511 270)
			(size 0.519938 1.4986)
			(layers "F.Cu" "F.Mask" "F.Paste")
			(net "TP_CHD_CPU0_DIMM1_FRU_0")
		)
		(pad "3" smd rect
			(at -2.050034 -61.624972 270)
			(size 0.519938 1.4986)
			(layers "F.Cu" "F.Mask" "F.Paste")
			(net "P3V3_AUX")
		)
		(pad "4" smd rect
			(at -2.050034 -60.775088 270)
			(size 0.519938 1.4986)
			(layers "F.Cu" "F.Mask" "F.Paste")
			(net "I3C_SPD_DDRABCD_CPU0_LVC1_SCL_6")
		)
		(pad "5" smd rect
			(at -2.050034 -59.92495 270)
			(size 0.519938 1.4986)
			(layers "F.Cu" "F.Mask" "F.Paste")
			(net "I3C_SPD_DDRABCD_CPU0_LVC1_SDA")
		)
		(pad "6" smd rect
			(at -2.050034 -59.075066 270)
			(size 0.519938 1.4986)
			(layers "F.Cu" "F.Mask" "F.Paste")
			(net "GND")
		)
		(pad "7" smd rect
			(at -2.050034 -58.224928 270)
			(size 0.519938 1.4986)
			(layers "F.Cu" "F.Mask" "F.Paste")
			(net "M_D_CPU0_SA_DQ<0>")
		)
		(pad "8" smd rect
			(at -2.050034 -57.375044 270)
			(size 0.519938 1.4986)
			(layers "F.Cu" "F.Mask" "F.Paste")
			(net "GND")
		)
		(pad "9" smd rect
			(at -2.050034 -56.524906 270)
			(size 0.519938 1.4986)
			(layers "F.Cu" "F.Mask" "F.Paste")
			(net "M_D_CPU0_SA_DQ<1>")
		)
		(pad "10" smd rect
			(at -2.050034 -55.675022 270)
			(size 0.519938 1.4986)
			(layers "F.Cu" "F.Mask" "F.Paste")
			(net "GND")
		)
		(pad "11" smd rect
			(at -2.050034 -54.824884 270)
			(size 0.519938 1.4986)
			(layers "F.Cu" "F.Mask" "F.Paste")
			(net "M_D_CPU0_SA_DQS_DP<0>")
		)
		(pad "12" smd rect
			(at -2.050034 -53.975 270)
			(size 0.519938 1.4986)
			(layers "F.Cu" "F.Mask" "F.Paste")
			(net "M_D_CPU0_SA_DQS_DN<0>")
		)
		(pad "13" smd rect
			(at -2.050034 -53.125116 270)
			(size 0.519938 1.4986)
			(layers "F.Cu" "F.Mask" "F.Paste")
			(net "GND")
		)
		(pad "14" smd rect
			(at -2.050034 -52.274978 270)
			(size 0.519938 1.4986)
			(layers "F.Cu" "F.Mask" "F.Paste")
			(net "M_D_CPU0_SA_DQ<4>")
		)
		(pad "15" smd rect
			(at -2.050034 -51.425094 270)
			(size 0.519938 1.4986)
			(layers "F.Cu" "F.Mask" "F.Paste")
			(net "GND")
		)
		(pad "16" smd rect
			(at -2.050034 -50.574956 270)
			(size 0.519938 1.4986)
			(layers "F.Cu" "F.Mask" "F.Paste")
			(net "M_D_CPU0_SA_DQ<5>")
		)
		(pad "17" smd rect
			(at -2.050034 -49.725072 270)
			(size 0.519938 1.4986)
			(layers "F.Cu" "F.Mask" "F.Paste")
			(net "GND")
		)
		(pad "18" smd rect
			(at -2.050034 -48.874934 270)
			(size 0.519938 1.4986)
			(layers "F.Cu" "F.Mask" "F.Paste")
			(net "M_D_CPU0_SA_DQ<8>")
		)
		(pad "19" smd rect
			(at -2.050034 -48.02505 270)
			(size 0.519938 1.4986)
			(layers "F.Cu" "F.Mask" "F.Paste")
			(net "GND")
		)
		(pad "20" smd rect
			(at -2.050034 -47.174912 270)
			(size 0.519938 1.4986)
			(layers "F.Cu" "F.Mask" "F.Paste")
			(net "M_D_CPU0_SA_DQ<9>")
		)
		(pad "21" smd rect
			(at -2.050034 -46.325028 270)
			(size 0.519938 1.4986)
			(layers "F.Cu" "F.Mask" "F.Paste")
			(net "GND")
		)
		(pad "22" smd rect
			(at -2.050034 -45.47489 270)
			(size 0.519938 1.4986)
			(layers "F.Cu" "F.Mask" "F.Paste")
			(net "M_D_CPU0_SA_DQS_DP<1>")
		)
		(pad "23" smd rect
			(at -2.050034 -44.625006 270)
			(size 0.519938 1.4986)
			(layers "F.Cu" "F.Mask" "F.Paste")
			(net "M_D_CPU0_SA_DQS_DN<1>")
		)
		(pad "24" smd rect
			(at -2.050034 -43.775122 270)
			(size 0.519938 1.4986)
			(layers "F.Cu" "F.Mask" "F.Paste")
			(net "GND")
		)
		(pad "25" smd rect
			(at -2.050034 -42.924984 270)
			(size 0.519938 1.4986)
			(layers "F.Cu" "F.Mask" "F.Paste")
			(net "M_D_CPU0_SA_DQ<12>")
		)
		(pad "26" smd rect
			(at -2.050034 -42.0751 270)
			(size 0.519938 1.4986)
			(layers "F.Cu" "F.Mask" "F.Paste")
			(net "GND")
		)
		(pad "27" smd rect
			(at -2.050034 -41.224962 270)
			(size 0.519938 1.4986)
			(layers "F.Cu" "F.Mask" "F.Paste")
			(net "M_D_CPU0_SA_DQ<13>")
		)
		(pad "28" smd rect
			(at -2.050034 -40.375078 270)
			(size 0.519938 1.4986)
			(layers "F.Cu" "F.Mask" "F.Paste")
			(net "GND")
		)
		(pad "29" smd rect
			(at -2.050034 -39.52494 270)
			(size 0.519938 1.4986)
			(layers "F.Cu" "F.Mask" "F.Paste")
			(net "M_D_CPU0_SA_DQ<16>")
		)
		(pad "30" smd rect
			(at -2.050034 -38.675056 270)
			(size 0.519938 1.4986)
			(layers "F.Cu" "F.Mask" "F.Paste")
			(net "GND")
		)
		(pad "31" smd rect
			(at -2.050034 -37.824918 270)
			(size 0.519938 1.4986)
			(layers "F.Cu" "F.Mask" "F.Paste")
			(net "M_D_CPU0_SA_DQ<17>")
		)
		(pad "32" smd rect
			(at -2.050034 -36.975034 270)
			(size 0.519938 1.4986)
			(layers "F.Cu" "F.Mask" "F.Paste")
			(net "GND")
		)
		(pad "33" smd rect
			(at -2.050034 -36.124896 270)
			(size 0.519938 1.4986)
			(layers "F.Cu" "F.Mask" "F.Paste")
			(net "M_D_CPU0_SA_DQS_DP<2>")
		)
		(pad "34" smd rect
			(at -2.050034 -35.275012 270)
			(size 0.519938 1.4986)
			(layers "F.Cu" "F.Mask" "F.Paste")
			(net "M_D_CPU0_SA_DQS_DN<2>")
		)
		(pad "35" smd rect
			(at -2.050034 -34.425128 270)
			(size 0.519938 1.4986)
			(layers "F.Cu" "F.Mask" "F.Paste")
			(net "GND")
		)
		(pad "36" smd rect
			(at -2.050034 -33.57499 270)
			(size 0.519938 1.4986)
			(layers "F.Cu" "F.Mask" "F.Paste")
			(net "M_D_CPU0_SA_DQ<20>")
		)
		(pad "37" smd rect
			(at -2.050034 -32.725106 270)
			(size 0.519938 1.4986)
			(layers "F.Cu" "F.Mask" "F.Paste")
			(net "GND")
		)
		(pad "38" smd rect
			(at -2.050034 -31.874968 270)
			(size 0.519938 1.4986)
			(layers "F.Cu" "F.Mask" "F.Paste")
			(net "M_D_CPU0_SA_DQ<21>")
		)
		(pad "39" smd rect
			(at -2.050034 -31.025084 270)
			(size 0.519938 1.4986)
			(layers "F.Cu" "F.Mask" "F.Paste")
			(net "GND")
		)
		(pad "40" smd rect
			(at -2.050034 -30.174946 270)
			(size 0.519938 1.4986)
			(layers "F.Cu" "F.Mask" "F.Paste")
			(net "M_D_CPU0_SA_DQ<24>")
		)
		(pad "41" smd rect
			(at -2.050034 -29.325062 270)
			(size 0.519938 1.4986)
			(layers "F.Cu" "F.Mask" "F.Paste")
			(net "GND")
		)
		(pad "42" smd rect
			(at -2.050034 -28.474924 270)
			(size 0.519938 1.4986)
			(layers "F.Cu" "F.Mask" "F.Paste")
			(net "M_D_CPU0_SA_DQ<25>")
		)
		(pad "43" smd rect
			(at -2.050034 -27.62504 270)
			(size 0.519938 1.4986)
			(layers "F.Cu" "F.Mask" "F.Paste")
			(net "GND")
		)
		(pad "44" smd rect
			(at -2.050034 -26.774902 270)
			(size 0.519938 1.4986)
			(layers "F.Cu" "F.Mask" "F.Paste")
			(net "M_D_CPU0_SA_DQS_DP<3>")
		)
		(pad "45" smd rect
			(at -2.050034 -25.925018 270)
			(size 0.519938 1.4986)
			(layers "F.Cu" "F.Mask" "F.Paste")
			(net "M_D_CPU0_SA_DQS_DN<3>")
		)
	)
)
